# T6G (Grand Teton) — schematic netlist excerpt (pin names and nets, part order shuffled) for the footprints in the layout excerpt that follows; sources: Cadence DE-HDL packaged netlist, KiCad conversion of 04192023_DAF0TMB3IC0_F0TG_MB_C_brd_V02_OCP.brd

R849  Q_RES  10K 1% CHIP  pkg 0201LF  page 185 : A = RST_SMB_RT_ROM_R1_N ; B = GND
C465  Q_CAP  1000PF 50V 5% EMPTY  pkg 0402  page 193 : A = PWRGD_PVDDCR_SOC_P0_R ; B = GND
C2414  Q_CAP  22UF 4V 20% X6S  pkg C0402  page 74 : A = PVDDCR_SOC_P1 ; B = GND

(kicad_pcb
	(version 20260206)
	(generator "pcbnew")
	(generator_version "10.0")
	(general
		(thickness 1.6)
		(legacy_teardrops no)
	)
	(paper "A4")
	(title_block
		(title "04192023_DAF0TMB3IC0_F0TG_MB_C_brd_V02_OCP.brd")
		(comment 1 "Grand Teton / footprints 6137-6139 of 8354")
	)
	(layers
		(0 "F.Cu" signal "TOP")
		(4 "In1.Cu" signal "GND")
		(6 "In2.Cu" signal "IN1")
		(8 "In3.Cu" signal "GND1")
		(10 "In4.Cu" signal "IN2")
		(12 "In5.Cu" signal "GND2")
		(14 "In6.Cu" signal "IN3")
		(16 "In7.Cu" signal "GND3")
		(18 "In8.Cu" signal "VCC")
		(20 "In9.Cu" signal "VCC1")
		(22 "In10.Cu" signal "GND4")
		(24 "In11.Cu" signal "IN4")
		(26 "In12.Cu" signal "GND5")
		(28 "In13.Cu" signal "IN5")
		(30 "In14.Cu" signal "GND6")
		(32 "In15.Cu" signal "IN6")
		(34 "In16.Cu" signal "GND7")
		(2 "B.Cu" signal "BOTTOM")
		(9 "F.Adhes" user "F.Adhesive")
		(11 "B.Adhes" user "B.Adhesive")
		(13 "F.Paste" user "Package Geometry/Pastemask Top")
		(15 "B.Paste" user "Package Geometry/Pastemask Bottom")
		(5 "F.SilkS" user "Ref Des/Silkscreen Top")
		(7 "B.SilkS" user "Ref Des/Silkscreen Bottom")
		(1 "F.Mask" user "Board Geometry/Soldermask Top")
		(3 "B.Mask" user "Board Geometry/Soldermask Bottom")
		(17 "Dwgs.User" user "User.Drawings")
		(19 "Cmts.User" user "User.Comments")
		(21 "Eco1.User" user "User.Eco1")
		(23 "Eco2.User" user "User.Eco2")
		(25 "Edge.Cuts" user "Board Geometry/Outline")
		(27 "Margin" user)
		(31 "F.CrtYd" user "Package Geometry/Place Bound Top")
		(29 "B.CrtYd" user "Package Geometry/Place Bound Bottom")
		(35 "F.Fab" user "Ref Des/Assembly Top")
		(33 "B.Fab" user "Ref Des/Assembly Bottom")
	)
	(footprint ""
		(layer "B.Cu")
		(at 117.896386 -250.892564)
		(property "Reference" "C2414"
			(at 0 0 0)
			(layer "B.SilkS")
			(hide yes)
			(effects
				(font
					(size 1.27 1.27)
				)
				(justify mirror)
			)
		)
		(property "Value" ""
			(at 0 0 0)
			(layer "B.Fab")
			(effects
				(font
					(size 1.27 1.27)
				)
				(justify mirror)
			)
		)
		(duplicate_pad_numbers_are_jumpers no)
		(fp_line
			(start -0.7874 -0.4064)
			(end -0.7874 0.4064)
			(stroke
				(width 0.1524)
				(type default)
			)
			(layer "B.SilkS")
		)
		(fp_line
			(start -0.7874 0.4064)
			(end 0.7874 0.4064)
			(stroke
				(width 0.1524)
				(type default)
			)
			(layer "B.SilkS")
		)
		(fp_line
			(start 0.7874 -0.4064)
			(end -0.7874 -0.4064)
			(stroke
				(width 0.1524)
				(type default)
			)
			(layer "B.SilkS")
		)
		(fp_line
			(start 0.7874 0.4064)
			(end 0.7874 -0.4064)
			(stroke
				(width 0.1524)
				(type default)
			)
			(layer "B.SilkS")
		)
		(fp_line
			(start -0.67945 -0.3048)
			(end -0.67945 0.3048)
			(stroke
				(width 0.1)
				(type default)
			)
			(layer "B.Fab")
		)
		(fp_line
			(start -0.67945 0.3048)
			(end -0.120396 0.3048)
			(stroke
				(width 0.1)
				(type default)
			)
			(layer "B.Fab")
		)
		(fp_line
			(start -0.12065 -0.3048)
			(end -0.67945 -0.3048)
			(stroke
				(width 0.1)
				(type default)
			)
			(layer "B.Fab")
		)
		(fp_line
			(start -0.12065 -0.2794)
			(end -0.12065 -0.3048)
			(stroke
				(width 0.1)
				(type default)
			)
			(layer "B.Fab")
		)
		(fp_line
			(start -0.120396 0.2794)
			(end 0.12065 0.2794)
			(stroke
				(width 0.1)
				(type default)
			)
			(layer "B.Fab")
		)
		(fp_line
			(start -0.120396 0.3048)
			(end -0.120396 0.2794)
			(stroke
				(width 0.1)
				(type default)
			)
			(layer "B.Fab")
		)
		(fp_line
			(start 0.12065 -0.305054)
			(end 0.12065 -0.2794)
			(stroke
				(width 0.1)
				(type default)
			)
			(layer "B.Fab")
		)
		(fp_line
			(start 0.12065 -0.2794)
			(end -0.12065 -0.2794)
			(stroke
				(width 0.1)
				(type default)
			)
			(layer "B.Fab")
		)
		(fp_line
			(start 0.12065 0.2794)
			(end 0.12065 0.3048)
			(stroke
				(width 0.1)
				(type default)
			)
			(layer "B.Fab")
		)
		(fp_line
			(start 0.12065 0.3048)
			(end 0.67945 0.3048)
			(stroke
				(width 0.1)
				(type default)
			)
			(layer "B.Fab")
		)
		(fp_line
			(start 0.67945 -0.305054)
			(end 0.12065 -0.305054)
			(stroke
				(width 0.1)
				(type default)
			)
			(layer "B.Fab")
		)
		(fp_line
			(start 0.67945 0.3048)
			(end 0.67945 -0.305054)
			(stroke
				(width 0.1)
				(type default)
			)
			(layer "B.Fab")
		)
		(pad "1" smd circle
			(at 0.40005 0 180)
			(size 0 0)
			(layers "B.Cu" "B.Mask" "B.Paste")
			(net "PVDDCR_SOC_P1")
		)
		(pad "2" smd circle
			(at -0.40005 0 180)
			(size 0 0)
			(layers "B.Cu" "B.Mask" "B.Paste")
			(net "GND")
		)
	)
	(footprint ""
		(layer "B.Cu")
		(at 239.141 -332.613)
		(property "Reference" "R849"
			(at 0 0 0)
			(layer "B.SilkS")
			(hide yes)
			(effects
				(font
					(size 1.27 1.27)
				)
				(justify mirror)
			)
		)
		(property "Value" ""
			(at 0 0 0)
			(layer "B.Fab")
			(effects
				(font
					(size 1.27 1.27)
				)
				(justify mirror)
			)
		)
		(duplicate_pad_numbers_are_jumpers no)
		(fp_line
			(start -0.32512 -0.175006)
			(end -0.32512 0.175006)
			(stroke
				(width 0.1)
				(type default)
			)
			(layer "B.Fab")
		)
		(fp_line
			(start -0.32512 0.175006)
			(end 0.32512 0.175006)
			(stroke
				(width 0.1)
				(type default)
			)
			(layer "B.Fab")
		)
		(fp_line
			(start 0.32512 -0.175006)
			(end -0.32512 -0.175006)
			(stroke
				(width 0.1)
				(type default)
			)
			(layer "B.Fab")
		)
		(fp_line
			(start 0.32512 0.175006)
			(end 0.32512 -0.175006)
			(stroke
				(width 0.1)
				(type default)
			)
			(layer "B.Fab")
		)
		(pad "1" smd rect
			(at 0.2667 0 180)
			(size 0.3048 0.381)
			(layers "B.Cu" "B.Mask" "B.Paste")
			(net "RST_SMB_RT_ROM_R1_N")
		)
		(pad "2" smd rect
			(at -0.2667 0)
			(size 0.3048 0.381)
			(layers "B.Cu" "B.Mask" "B.Paste")
			(net "GND")
		)
	)
	(footprint ""
		(layer "B.Cu")
		(at 372.937278 -143.504158)
		(property "Reference" "C465"
			(at 0 0 0)
			(layer "B.SilkS")
			(hide yes)
			(effects
				(font
					(size 1.27 1.27)
				)
				(justify mirror)
			)
		)
		(property "Value" ""
			(at 0 0 0)
			(layer "B.Fab")
			(effects
				(font
					(size 1.27 1.27)
				)
				(justify mirror)
			)
		)
		(duplicate_pad_numbers_are_jumpers no)
		(fp_line
			(start -0.7874 -0.4064)
			(end -0.7874 0.4064)
			(stroke
				(width 0.1524)
				(type default)
			)
			(layer "B.SilkS")
		)
		(fp_line
			(start -0.7874 0.4064)
			(end 0.7874 0.4064)
			(stroke
				(width 0.1524)
				(type default)
			)
			(layer "B.SilkS")
		)
		(fp_line
			(start 0.7874 -0.4064)
			(end -0.7874 -0.4064)
			(stroke
				(width 0.1524)
				(type default)
			)
			(layer "B.SilkS")
		)
		(fp_line
			(start 0.7874 0.4064)
			(end 0.7874 -0.4064)
			(stroke
				(width 0.1524)
				(type default)
			)
			(layer "B.SilkS")
		)
		(fp_line
			(start -0.67945 -0.3048)
			(end -0.67945 0.3048)
			(stroke
				(width 0.1)
				(type default)
			)
			(layer "B.Fab")
		)
		(fp_line
			(start -0.67945 0.3048)
			(end -0.120396 0.3048)
			(stroke
				(width 0.1)
				(type default)
			)
			(layer "B.Fab")
		)
		(fp_line
			(start -0.12065 -0.3048)
			(end -0.67945 -0.3048)
			(stroke
				(width 0.1)
				(type default)
			)
			(layer "B.Fab")
		)
		(fp_line
			(start -0.12065 -0.2794)
			(end -0.12065 -0.3048)
			(stroke
				(width 0.1)
				(type default)
			)
			(layer "B.Fab")
		)
		(fp_line
			(start -0.120396 0.2794)
			(end 0.12065 0.2794)
			(stroke
				(width 0.1)
				(type default)
			)
			(layer "B.Fab")
		)
		(fp_line
			(start -0.120396 0.3048)
			(end -0.120396 0.2794)
			(stroke
				(width 0.1)
				(type default)
			)
			(layer "B.Fab")
		)
		(fp_line
			(start 0.12065 -0.305054)
			(end 0.12065 -0.2794)
			(stroke
				(width 0.1)
				(type default)
			)
			(layer "B.Fab")
		)
		(fp_line
			(start 0.12065 -0.2794)
			(end -0.12065 -0.2794)
			(stroke
				(width 0.1)
				(type default)
			)
			(layer "B.Fab")
		)
		(fp_line
			(start 0.12065 0.2794)
			(end 0.12065 0.3048)
			(stroke
				(width 0.1)
				(type default)
			)
			(layer "B.Fab")
		)
		(fp_line
			(start 0.12065 0.3048)
			(end 0.67945 0.3048)
			(stroke
				(width 0.1)
				(type default)
			)
			(layer "B.Fab")
		)
		(fp_line
			(start 0.67945 -0.305054)
			(end 0.12065 -0.305054)
			(stroke
				(width 0.1)
				(type default)
			)
			(layer "B.Fab")
		)
		(fp_line
			(start 0.67945 0.3048)
			(end 0.67945 -0.305054)
			(stroke
				(width 0.1)
				(type default)
			)
			(layer "B.Fab")
		)
		(pad "1" smd circle
			(at 0.40005 0 180)
			(size 0 0)
			(layers "B.Cu" "B.Mask" "B.Paste")
			(net "PWRGD_PVDDCR_SOC_P0_R")
		)
		(pad "2" smd circle
			(at -0.40005 0 180)
			(size 0 0)
			(layers "B.Cu" "B.Mask" "B.Paste")
			(net "GND")
		)
	)
)
